(kicad_pcb
	(version 20260206)
	(generator "pcbnew")
	(generator_version "10.0")
	(general
		(thickness 1.6)
		(legacy_teardrops no)
	)
	(paper "A4")
	(title_block
		(title "Bryce Canyon_IOM_IOC_16318-2_OCP.brd")
		(comment 1 "Bryce Canyon / footprints 1364-1371 of 1605")
	)
	(layers
		(0 "F.Cu" signal "TOP")
		(4 "In1.Cu" signal "L2GND")
		(6 "In2.Cu" signal "L3")
		(8 "In3.Cu" signal "L4VCC")
		(10 "In4.Cu" signal "L5VCC")
		(12 "In5.Cu" signal "L6")
		(14 "In6.Cu" signal "L7GND")
		(2 "B.Cu" signal "BOTTOM")
		(9 "F.Adhes" user "F.Adhesive")
		(11 "B.Adhes" user "B.Adhesive")
		(13 "F.Paste" user "Package Geometry/Pastemask Top")
		(15 "B.Paste" user "Package Geometry/Pastemask Bottom")
		(5 "F.SilkS" user "Ref Des/Silkscreen Top")
		(7 "B.SilkS" user "Ref Des/Silkscreen Bottom")
		(1 "F.Mask" user "Board Geometry/Soldermask Top")
		(3 "B.Mask" user "Board Geometry/Soldermask Bottom")
		(17 "Dwgs.User" user "User.Drawings")
		(19 "Cmts.User" user "User.Comments")
		(21 "Eco1.User" user "User.Eco1")
		(23 "Eco2.User" user "User.Eco2")
		(25 "Edge.Cuts" user "Board Geometry/Outline")
		(27 "Margin" user)
		(31 "F.CrtYd" user "Package Geometry/Place Bound Top")
		(29 "B.CrtYd" user "Package Geometry/Place Bound Bottom")
		(35 "F.Fab" user "Ref Des/Assembly Top")
		(33 "B.Fab" user "Ref Des/Assembly Bottom")
	)
	(footprint ""
		(layer "B.Cu")
		(at 189.2681 -61.6204 90)
		(property "Reference" "C411"
			(at 0 0 90)
			(layer "B.SilkS")
			(hide yes)
			(effects
				(font
					(size 1.27 1.27)
				)
				(justify mirror)
			)
		)
		(property "Value" "SCD1U6D3V1KX-GP"
			(at 2.8321 -1.7399 90)
			(unlocked yes)
			(layer "B.Fab")
			(hide yes)
			(effects
				(font
					(size 1.016 1.016)
					(thickness 0.1524)
				)
				(justify mirror)
			)
		)
		(property "Device Type" "C0201H13"
			(at 2.8321 -3.2639 90)
			(unlocked yes)
			(layer "B.Fab")
			(hide yes)
			(effects
				(font
					(size 1.016 1.016)
					(thickness 0.1524)
				)
				(justify mirror)
			)
		)
		(duplicate_pad_numbers_are_jumpers no)
		(fp_rect
			(start 0.2794 0.6477)
			(end -0.2794 -0.6477)
			(stroke
				(width 0)
				(type default)
			)
			(fill no)
			(layer "B.CrtYd")
		)
		(fp_rect
			(start 0.2794 0.6477)
			(end -0.2794 -0.6477)
			(stroke
				(width 0)
				(type default)
			)
			(fill no)
			(layer "B.Fab")
		)
		(pad "1" smd custom
			(at 0 -0.2794 270)
			(size 0.0762 0.0762)
			(layers "B.Cu" "B.Mask" "B.Paste")
			(net "P0V975")
			(options
				(clearance outline)
				(anchor circle)
			)
			(primitives
				(gr_poly
					(pts
						(arc
							(start 0.1524 0.127)
							(mid 0.137521 0.162921)
							(end 0.1016 0.1778)
						)
						(arc
							(start -0.1016 0.1778)
							(mid -0.137521 0.162921)
							(end -0.1524 0.127)
						)
						(arc
							(start -0.1524 -0.127)
							(mid -0.137521 -0.162921)
							(end -0.1016 -0.1778)
						)
						(arc
							(start 0.1016 -0.1778)
							(mid 0.137521 -0.162921)
							(end 0.1524 -0.127)
						)
					)
					(width 0)
					(fill yes)
				)
			)
		)
		(pad "2" smd custom
			(at 0 0.2794 270)
			(size 0.0762 0.0762)
			(layers "B.Cu" "B.Mask" "B.Paste")
			(net "GND")
			(options
				(clearance outline)
				(anchor circle)
			)
			(primitives
				(gr_poly
					(pts
						(arc
							(start 0.1524 0.127)
							(mid 0.137521 0.162921)
							(end 0.1016 0.1778)
						)
						(arc
							(start -0.1016 0.1778)
							(mid -0.137521 0.162921)
							(end -0.1524 0.127)
						)
						(arc
							(start -0.1524 -0.127)
							(mid -0.137521 -0.162921)
							(end -0.1016 -0.1778)
						)
						(arc
							(start 0.1016 -0.1778)
							(mid 0.137521 -0.162921)
							(end 0.1524 -0.127)
						)
					)
					(width 0)
					(fill yes)
				)
			)
		)
	)
	(footprint ""
		(layer "B.Cu")
		(at 23.437342 -129.1082 180)
		(property "Reference" "R248"
			(at 0 0 0)
			(layer "B.SilkS")
			(hide yes)
			(effects
				(font
					(size 1.27 1.27)
				)
				(justify mirror)
			)
		)
		(property "Value" "120R2F-GP"
			(at -0.064008 -3.993896 180)
			(unlocked yes)
			(layer "B.Fab")
			(hide yes)
			(effects
				(font
					(size 1.016 1.016)
					(thickness 0.1524)
				)
				(justify mirror)
			)
		)
		(property "Device Type" "R402H16"
			(at -0.064008 -5.517896 180)
			(unlocked yes)
			(layer "B.Fab")
			(hide yes)
			(effects
				(font
					(size 1.016 1.016)
					(thickness 0.1524)
				)
				(justify mirror)
			)
		)
		(duplicate_pad_numbers_are_jumpers no)
		(fp_line
			(start 0.508 -0.9398)
			(end 0.508 0.9398)
			(stroke
				(width 0.1524)
				(type default)
			)
			(layer "B.SilkS")
		)
		(fp_line
			(start -0.508 -0.9398)
			(end 0.508 -0.9398)
			(stroke
				(width 0.1524)
				(type default)
			)
			(layer "B.SilkS")
		)
		(fp_rect
			(start 0.508 0.9398)
			(end -0.508 -0.9398)
			(stroke
				(width 0)
				(type default)
			)
			(fill no)
			(layer "B.CrtYd")
		)
		(fp_rect
			(start 0.508 0.9398)
			(end -0.508 -0.9398)
			(stroke
				(width 0)
				(type default)
			)
			(fill no)
			(layer "B.Fab")
		)
		(pad "1" smd custom
			(at 0 -0.4445)
			(size 0.1397 0.1397)
			(layers "B.Cu" "B.Mask" "B.Paste")
			(net "GND")
			(options
				(clearance outline)
				(anchor circle)
			)
			(primitives
				(gr_poly
					(pts
						(arc
							(start -0.1778 0.2794)
							(mid -0.249642 0.249642)
							(end -0.2794 0.1778)
						)
						(arc
							(start -0.2794 -0.1778)
							(mid -0.249642 -0.249642)
							(end -0.1778 -0.2794)
						)
						(arc
							(start 0.1778 -0.2794)
							(mid 0.249642 -0.249642)
							(end 0.2794 -0.1778)
						)
						(arc
							(start 0.2794 0.1778)
							(mid 0.249642 0.249642)
							(end 0.1778 0.2794)
						)
					)
					(width 0)
					(fill yes)
				)
			)
		)
		(pad "2" smd custom
			(at 0 0.4445)
			(size 0.1397 0.1397)
			(layers "B.Cu" "B.Mask" "B.Paste")
			(net "MEMA_7")
			(options
				(clearance outline)
				(anchor circle)
			)
			(primitives
				(gr_poly
					(pts
						(arc
							(start -0.1778 0.2794)
							(mid -0.249642 0.249642)
							(end -0.2794 0.1778)
						)
						(arc
							(start -0.2794 -0.1778)
							(mid -0.249642 -0.249642)
							(end -0.1778 -0.2794)
						)
						(arc
							(start 0.1778 -0.2794)
							(mid 0.249642 -0.249642)
							(end 0.2794 -0.1778)
						)
						(arc
							(start 0.2794 0.1778)
							(mid 0.249642 0.249642)
							(end 0.1778 0.2794)
						)
					)
					(width 0)
					(fill yes)
				)
			)
		)
	)
	(footprint ""
		(layer "B.Cu")
		(at 200.8632 -75.3364)
		(property "Reference" "C365"
			(at 0 0 0)
			(layer "B.SilkS")
			(hide yes)
			(effects
				(font
					(size 1.27 1.27)
				)
				(justify mirror)
			)
		)
		(property "Value" "SCD1U6D3V1KX-GP"
			(at 2.8321 -1.7399 0)
			(unlocked yes)
			(layer "B.Fab")
			(hide yes)
			(effects
				(font
					(size 1.016 1.016)
					(thickness 0.1524)
				)
				(justify mirror)
			)
		)
		(property "Device Type" "C0201H13"
			(at 2.8321 -3.2639 0)
			(unlocked yes)
			(layer "B.Fab")
			(hide yes)
			(effects
				(font
					(size 1.016 1.016)
					(thickness 0.1524)
				)
				(justify mirror)
			)
		)
		(duplicate_pad_numbers_are_jumpers no)
		(fp_rect
			(start 0.2794 0.6477)
			(end -0.2794 -0.6477)
			(stroke
				(width 0)
				(type default)
			)
			(fill no)
			(layer "B.CrtYd")
		)
		(fp_rect
			(start 0.2794 0.6477)
			(end -0.2794 -0.6477)
			(stroke
				(width 0)
				(type default)
			)
			(fill no)
			(layer "B.Fab")
		)
		(pad "1" smd custom
			(at 0 -0.2794 180)
			(size 0.0762 0.0762)
			(layers "B.Cu" "B.Mask" "B.Paste")
			(net "PCE_AVDD")
			(options
				(clearance outline)
				(anchor circle)
			)
			(primitives
				(gr_poly
					(pts
						(arc
							(start 0.1524 0.127)
							(mid 0.137521 0.162921)
							(end 0.1016 0.1778)
						)
						(arc
							(start -0.1016 0.1778)
							(mid -0.137521 0.162921)
							(end -0.1524 0.127)
						)
						(arc
							(start -0.1524 -0.127)
							(mid -0.137521 -0.162921)
							(end -0.1016 -0.1778)
						)
						(arc
							(start 0.1016 -0.1778)
							(mid 0.137521 -0.162921)
							(end 0.1524 -0.127)
						)
					)
					(width 0)
					(fill yes)
				)
			)
		)
		(pad "2" smd custom
			(at 0 0.2794 180)
			(size 0.0762 0.0762)
			(layers "B.Cu" "B.Mask" "B.Paste")
			(net "GND")
			(options
				(clearance outline)
				(anchor circle)
			)
			(primitives
				(gr_poly
					(pts
						(arc
							(start 0.1524 0.127)
							(mid 0.137521 0.162921)
							(end 0.1016 0.1778)
						)
						(arc
							(start -0.1016 0.1778)
							(mid -0.137521 0.162921)
							(end -0.1524 0.127)
						)
						(arc
							(start -0.1524 -0.127)
							(mid -0.137521 -0.162921)
							(end -0.1016 -0.1778)
						)
						(arc
							(start 0.1016 -0.1778)
							(mid 0.137521 -0.162921)
							(end 0.1524 -0.127)
						)
					)
					(width 0)
					(fill yes)
				)
			)
		)
	)
	(footprint ""
		(layer "B.Cu")
		(at 189.171072 -76.419456)
		(property "Reference" "TP131"
			(at 0 0 0)
			(layer "B.SilkS")
			(hide yes)
			(effects
				(font
					(size 1.27 1.27)
				)
				(justify mirror)
			)
		)
		(property "Value" "TPAD28-2-GP"
			(at 0.0127 -1.6637 0)
			(unlocked yes)
			(layer "B.Fab")
			(hide yes)
			(effects
				(font
					(size 1.016 1.016)
					(thickness 0.1524)
				)
				(justify mirror)
			)
		)
		(property "Device Type" "TPAD28"
			(at 0.0127 -3.1877 0)
			(unlocked yes)
			(layer "B.Fab")
			(hide yes)
			(effects
				(font
					(size 1.016 1.016)
					(thickness 0.1524)
				)
				(justify mirror)
			)
		)
		(duplicate_pad_numbers_are_jumpers no)
		(fp_poly
			(pts
				(arc
					(start 0.3556 0)
					(mid -0.3556 0)
					(end 0.3556 0)
				)
			)
			(stroke
				(width 0)
				(type default)
			)
			(fill no)
			(layer "B.CrtYd")
		)
		(fp_poly
			(pts
				(arc
					(start 0.6096 0)
					(mid -0.6096 0)
					(end 0.6096 0)
				)
			)
			(stroke
				(width 0)
				(type default)
			)
			(fill no)
			(layer "B.Fab")
		)
		(pad "1" smd circle
			(at 0 0 180)
			(size 0.7112 0.7112)
			(layers "B.Cu" "B.Mask" "B.Paste")
			(net "IOC_UART_1_TX")
		)
	)
	(footprint ""
		(layer "B.Cu")
		(at 60.9219 -155.15844 -90)
		(property "Reference" "R304"
			(at 0 0 90)
			(layer "B.SilkS")
			(hide yes)
			(effects
				(font
					(size 1.27 1.27)
				)
				(justify mirror)
			)
		)
		(property "Value" "47KR2F-GP"
			(at -0.064008 -3.993896 270)
			(unlocked yes)
			(layer "B.Fab")
			(hide yes)
			(effects
				(font
					(size 1.016 1.016)
					(thickness 0.1524)
				)
				(justify mirror)
			)
		)
		(property "Device Type" "R402H16"
			(at -0.064008 -5.517896 270)
			(unlocked yes)
			(layer "B.Fab")
			(hide yes)
			(effects
				(font
					(size 1.016 1.016)
					(thickness 0.1524)
				)
				(justify mirror)
			)
		)
		(duplicate_pad_numbers_are_jumpers no)
		(fp_line
			(start -0.508 -0.9398)
			(end 0.508 -0.9398)
			(stroke
				(width 0.1524)
				(type default)
			)
			(layer "B.SilkS")
		)
		(fp_line
			(start 0.508 -0.9398)
			(end 0.508 0.9398)
			(stroke
				(width 0.1524)
				(type default)
			)
			(layer "B.SilkS")
		)
		(fp_rect
			(start 0.508 0.9398)
			(end -0.508 -0.9398)
			(stroke
				(width 0)
				(type default)
			)
			(fill no)
			(layer "B.CrtYd")
		)
		(fp_rect
			(start 0.508 0.9398)
			(end -0.508 -0.9398)
			(stroke
				(width 0)
				(type default)
			)
			(fill no)
			(layer "B.Fab")
		)
		(pad "1" smd custom
			(at 0 -0.4445 90)
			(size 0.1397 0.1397)
			(layers "B.Cu" "B.Mask" "B.Paste")
			(net "GND")
			(options
				(clearance outline)
				(anchor circle)
			)
			(primitives
				(gr_poly
					(pts
						(arc
							(start -0.1778 0.2794)
							(mid -0.249642 0.249642)
							(end -0.2794 0.1778)
						)
						(arc
							(start -0.2794 -0.1778)
							(mid -0.249642 -0.249642)
							(end -0.1778 -0.2794)
						)
						(arc
							(start 0.1778 -0.2794)
							(mid 0.249642 -0.249642)
							(end 0.2794 -0.1778)
						)
						(arc
							(start 0.2794 0.1778)
							(mid 0.249642 0.249642)
							(end 0.1778 0.2794)
						)
					)
					(width 0)
					(fill yes)
				)
			)
		)
		(pad "2" smd custom
			(at 0 0.4445 90)
			(size 0.1397 0.1397)
			(layers "B.Cu" "B.Mask" "B.Paste")
			(net "BMC_RGMII_A4_D3")
			(options
				(clearance outline)
				(anchor circle)
			)
			(primitives
				(gr_poly
					(pts
						(arc
							(start -0.1778 0.2794)
							(mid -0.249642 0.249642)
							(end -0.2794 0.1778)
						)
						(arc
							(start -0.2794 -0.1778)
							(mid -0.249642 -0.249642)
							(end -0.1778 -0.2794)
						)
						(arc
							(start 0.1778 -0.2794)
							(mid 0.249642 -0.249642)
							(end 0.2794 -0.1778)
						)
						(arc
							(start 0.2794 0.1778)
							(mid 0.249642 0.249642)
							(end 0.1778 0.2794)
						)
					)
					(width 0)
					(fill yes)
				)
			)
		)
	)
	(footprint ""
		(layer "B.Cu")
		(at 184.910984 -77.139546)
		(property "Reference" "TP130"
			(at 0 0 0)
			(layer "B.SilkS")
			(hide yes)
			(effects
				(font
					(size 1.27 1.27)
				)
				(justify mirror)
			)
		)
		(property "Value" "TPAD28-2-GP"
			(at 0.0127 -1.6637 0)
			(unlocked yes)
			(layer "B.Fab")
			(hide yes)
			(effects
				(font
					(size 1.016 1.016)
					(thickness 0.1524)
				)
				(justify mirror)
			)
		)
		(property "Device Type" "TPAD28"
			(at 0.0127 -3.1877 0)
			(unlocked yes)
			(layer "B.Fab")
			(hide yes)
			(effects
				(font
					(size 1.016 1.016)
					(thickness 0.1524)
				)
				(justify mirror)
			)
		)
		(duplicate_pad_numbers_are_jumpers no)
		(fp_poly
			(pts
				(arc
					(start 0.3556 0)
					(mid -0.3556 0)
					(end 0.3556 0)
				)
			)
			(stroke
				(width 0)
				(type default)
			)
			(fill no)
			(layer "B.CrtYd")
		)
		(fp_poly
			(pts
				(arc
					(start 0.6096 0)
					(mid -0.6096 0)
					(end 0.6096 0)
				)
			)
			(stroke
				(width 0)
				(type default)
			)
			(fill no)
			(layer "B.Fab")
		)
		(pad "1" smd circle
			(at 0 0 180)
			(size 0.7112 0.7112)
			(layers "B.Cu" "B.Mask" "B.Paste")
			(net "IOC_UART_1_RX")
		)
	)
	(footprint ""
		(layer "B.Cu")
		(at 166.64559 -38.416738)
		(property "Reference" "C500"
			(at 0 0 0)
			(layer "B.SilkS")
			(hide yes)
			(effects
				(font
					(size 1.27 1.27)
				)
				(justify mirror)
			)
		)
		(property "Value" "SCD01U16V1KX-GP"
			(at 2.8321 -1.7399 0)
			(unlocked yes)
			(layer "B.Fab")
			(hide yes)
			(effects
				(font
					(size 1.016 1.016)
					(thickness 0.1524)
				)
				(justify mirror)
			)
		)
		(property "Device Type" "C0201H13"
			(at 2.8321 -3.2639 0)
			(unlocked yes)
			(layer "B.Fab")
			(hide yes)
			(effects
				(font
					(size 1.016 1.016)
					(thickness 0.1524)
				)
				(justify mirror)
			)
		)
		(duplicate_pad_numbers_are_jumpers no)
		(fp_rect
			(start 0.2794 0.6477)
			(end -0.2794 -0.6477)
			(stroke
				(width 0)
				(type default)
			)
			(fill no)
			(layer "B.CrtYd")
		)
		(fp_rect
			(start 0.2794 0.6477)
			(end -0.2794 -0.6477)
			(stroke
				(width 0)
				(type default)
			)
			(fill no)
			(layer "B.Fab")
		)
		(pad "1" smd custom
			(at 0 -0.2794 180)
			(size 0.0762 0.0762)
			(layers "B.Cu" "B.Mask" "B.Paste")
			(net "PHY_CON_B_TO_IOC_2_DP")
			(options
				(clearance outline)
				(anchor circle)
			)
			(primitives
				(gr_poly
					(pts
						(arc
							(start 0.1524 0.127)
							(mid 0.137521 0.162921)
							(end 0.1016 0.1778)
						)
						(arc
							(start -0.1016 0.1778)
							(mid -0.137521 0.162921)
							(end -0.1524 0.127)
						)
						(arc
							(start -0.1524 -0.127)
							(mid -0.137521 -0.162921)
							(end -0.1016 -0.1778)
						)
						(arc
							(start 0.1016 -0.1778)
							(mid 0.137521 -0.162921)
							(end 0.1524 -0.127)
						)
					)
					(width 0)
					(fill yes)
				)
			)
		)
		(pad "2" smd custom
			(at 0 0.2794 180)
			(size 0.0762 0.0762)
			(layers "B.Cu" "B.Mask" "B.Paste")
			(net "PHY_CON_B_TO_IOC_2_DP_C")
			(options
				(clearance outline)
				(anchor circle)
			)
			(primitives
				(gr_poly
					(pts
						(arc
							(start 0.1524 0.127)
							(mid 0.137521 0.162921)
							(end 0.1016 0.1778)
						)
						(arc
							(start -0.1016 0.1778)
							(mid -0.137521 0.162921)
							(end -0.1524 0.127)
						)
						(arc
							(start -0.1524 -0.127)
							(mid -0.137521 -0.162921)
							(end -0.1016 -0.1778)
						)
						(arc
							(start 0.1016 -0.1778)
							(mid 0.137521 -0.162921)
							(end 0.1524 -0.127)
						)
					)
					(width 0)
					(fill yes)
				)
			)
		)
	)
	(footprint ""
		(layer "B.Cu")
		(at 45.07484 -155.23972 -90)
		(property "Reference" "C103"
			(at 0 0 90)
			(layer "B.SilkS")
			(hide yes)
			(effects
				(font
					(size 1.27 1.27)
				)
				(justify mirror)
			)
		)
		(property "Value" "SCD1U16V2KX-3GP"
			(at -1.1811 -2.7051 270)
			(unlocked yes)
			(layer "B.Fab")
			(hide yes)
			(effects
				(font
					(size 1.016 1.016)
					(thickness 0.1524)
				)
				(justify mirror)
			)
		)
		(property "Device Type" "C402H22"
			(at -1.1811 -4.2291 270)
			(unlocked yes)
			(layer "B.Fab")
			(hide yes)
			(effects
				(font
					(size 1.016 1.016)
					(thickness 0.1524)
				)
				(justify mirror)
			)
		)
		(duplicate_pad_numbers_are_jumpers no)
		(fp_rect
			(start 0.4318 0.9525)
			(end -0.4318 -0.9525)
			(stroke
				(width 0)
				(type default)
			)
			(fill no)
			(layer "B.CrtYd")
		)
		(fp_rect
			(start 0.4318 0.9525)
			(end -0.4318 -0.9525)
			(stroke
				(width 0)
				(type default)
			)
			(fill no)
			(layer "B.Fab")
		)
		(pad "1" smd custom
			(at 0 -0.4445 90)
			(size 0.1524 0.1524)
			(layers "B.Cu" "B.Mask" "B.Paste")
			(net "V1PLLAV11")
			(options
				(clearance outline)
				(anchor circle)
			)
			(primitives
				(gr_poly
					(pts
						(arc
							(start 0.3048 0.2032)
							(mid 0.275042 0.275042)
							(end 0.2032 0.3048)
						)
						(arc
							(start -0.2032 0.3048)
							(mid -0.275042 0.275042)
							(end -0.3048 0.2032)
						)
						(arc
							(start -0.3048 -0.2032)
							(mid -0.275042 -0.275042)
							(end -0.2032 -0.3048)
						)
						(arc
							(start 0.2032 -0.3048)
							(mid 0.275042 -0.275042)
							(end 0.3048 -0.2032)
						)
					)
					(width 0)
					(fill yes)
				)
			)
		)
		(pad "2" smd custom
			(at 0 0.4445 90)
			(size 0.1524 0.1524)
			(layers "B.Cu" "B.Mask" "B.Paste")
			(net "GND")
			(options
				(clearance outline)
				(anchor circle)
			)
			(primitives
				(gr_poly
					(pts
						(arc
							(start 0.3048 0.2032)
							(mid 0.275042 0.275042)
							(end 0.2032 0.3048)
						)
						(arc
							(start -0.2032 0.3048)
							(mid -0.275042 0.275042)
							(end -0.3048 0.2032)
						)
						(arc
							(start -0.3048 -0.2032)
							(mid -0.275042 -0.275042)
							(end -0.2032 -0.3048)
						)
						(arc
							(start 0.2032 -0.3048)
							(mid 0.275042 -0.275042)
							(end 0.3048 -0.2032)
						)
					)
					(width 0)
					(fill yes)
				)
			)
		)
	)
)
